# T6G (Grand Teton) — schematic netlist excerpt (pin names and nets, part order shuffled) for the footprints in the layout excerpt that follows; sources: Cadence DE-HDL packaged netlist, KiCad conversion of 04192023_DAF0TMB3IC0_F0TG_MB_C_brd_V02_OCP.brd

C1111  Q_CAP  0.1UF 25V 10% X7R  pkg 0402  page 357 : A = VSENSE_P12V_INA230_6_INP ; B = VSENSE_P12V_INA230_6_INN
R3704  Q_RES  1K 1% CHIP  pkg 0402LF  page 252 : A = PCA9548_PCIE0_ADDR2 ; B = GND

(kicad_pcb
	(version 20260206)
	(generator "pcbnew")
	(generator_version "10.0")
	(general
		(thickness 1.6)
		(legacy_teardrops no)
	)
	(paper "A4")
	(title_block
		(title "04192023_DAF0TMB3IC0_F0TG_MB_C_brd_V02_OCP.brd")
		(comment 1 "Grand Teton / footprints 1154-1155 of 8354")
	)
	(layers
		(0 "F.Cu" signal "TOP")
		(4 "In1.Cu" signal "GND")
		(6 "In2.Cu" signal "IN1")
		(8 "In3.Cu" signal "GND1")
		(10 "In4.Cu" signal "IN2")
		(12 "In5.Cu" signal "GND2")
		(14 "In6.Cu" signal "IN3")
		(16 "In7.Cu" signal "GND3")
		(18 "In8.Cu" signal "VCC")
		(20 "In9.Cu" signal "VCC1")
		(22 "In10.Cu" signal "GND4")
		(24 "In11.Cu" signal "IN4")
		(26 "In12.Cu" signal "GND5")
		(28 "In13.Cu" signal "IN5")
		(30 "In14.Cu" signal "GND6")
		(32 "In15.Cu" signal "IN6")
		(34 "In16.Cu" signal "GND7")
		(2 "B.Cu" signal "BOTTOM")
		(9 "F.Adhes" user "F.Adhesive")
		(11 "B.Adhes" user "B.Adhesive")
		(13 "F.Paste" user "Package Geometry/Pastemask Top")
		(15 "B.Paste" user "Package Geometry/Pastemask Bottom")
		(5 "F.SilkS" user "Ref Des/Silkscreen Top")
		(7 "B.SilkS" user "Ref Des/Silkscreen Bottom")
		(1 "F.Mask" user "Board Geometry/Soldermask Top")
		(3 "B.Mask" user "Board Geometry/Soldermask Bottom")
		(17 "Dwgs.User" user "User.Drawings")
		(19 "Cmts.User" user "User.Comments")
		(21 "Eco1.User" user "User.Eco1")
		(23 "Eco2.User" user "User.Eco2")
		(25 "Edge.Cuts" user "Board Geometry/Outline")
		(27 "Margin" user)
		(31 "F.CrtYd" user "Package Geometry/Place Bound Top")
		(29 "B.CrtYd" user "Package Geometry/Place Bound Bottom")
		(35 "F.Fab" user "Ref Des/Assembly Top")
		(33 "B.Fab" user "Ref Des/Assembly Bottom")
	)
	(footprint ""
		(layer "F.Cu")
		(at 271.085056 -121.83237)
		(property "Reference" "R3704"
			(at 0 0 0)
			(layer "F.SilkS")
			(hide yes)
			(effects
				(font
					(size 1.27 1.27)
				)
			)
		)
		(property "Value" ""
			(at 0 0 0)
			(layer "F.Fab")
			(effects
				(font
					(size 1.27 1.27)
				)
			)
		)
		(duplicate_pad_numbers_are_jumpers no)
		(fp_line
			(start -0.7874 -0.4064)
			(end 0.7874 -0.4064)
			(stroke
				(width 0.1524)
				(type default)
			)
			(layer "F.SilkS")
		)
		(fp_line
			(start -0.7874 0.4064)
			(end -0.7874 -0.4064)
			(stroke
				(width 0.1524)
				(type default)
			)
			(layer "F.SilkS")
		)
		(fp_line
			(start 0.7874 -0.4064)
			(end 0.7874 0.4064)
			(stroke
				(width 0.1524)
				(type default)
			)
			(layer "F.SilkS")
		)
		(fp_line
			(start 0.7874 0.4064)
			(end -0.7874 0.4064)
			(stroke
				(width 0.1524)
				(type default)
			)
			(layer "F.SilkS")
		)
		(fp_line
			(start -0.67945 -0.305054)
			(end -0.12065 -0.305054)
			(stroke
				(width 0.1)
				(type default)
			)
			(layer "F.Fab")
		)
		(fp_line
			(start -0.67945 0.3048)
			(end -0.67945 -0.305054)
			(stroke
				(width 0.1)
				(type default)
			)
			(layer "F.Fab")
		)
		(fp_line
			(start -0.12065 -0.305054)
			(end -0.12065 -0.2794)
			(stroke
				(width 0.1)
				(type default)
			)
			(layer "F.Fab")
		)
		(fp_line
			(start -0.12065 -0.2794)
			(end 0.12065 -0.2794)
			(stroke
				(width 0.1)
				(type default)
			)
			(layer "F.Fab")
		)
		(fp_line
			(start -0.12065 0.2794)
			(end -0.12065 0.3048)
			(stroke
				(width 0.1)
				(type default)
			)
			(layer "F.Fab")
		)
		(fp_line
			(start -0.12065 0.3048)
			(end -0.67945 0.3048)
			(stroke
				(width 0.1)
				(type default)
			)
			(layer "F.Fab")
		)
		(fp_line
			(start 0.120396 0.2794)
			(end -0.12065 0.2794)
			(stroke
				(width 0.1)
				(type default)
			)
			(layer "F.Fab")
		)
		(fp_line
			(start 0.120396 0.3048)
			(end 0.120396 0.2794)
			(stroke
				(width 0.1)
				(type default)
			)
			(layer "F.Fab")
		)
		(fp_line
			(start 0.12065 -0.3048)
			(end 0.67945 -0.3048)
			(stroke
				(width 0.1)
				(type default)
			)
			(layer "F.Fab")
		)
		(fp_line
			(start 0.12065 -0.2794)
			(end 0.12065 -0.3048)
			(stroke
				(width 0.1)
				(type default)
			)
			(layer "F.Fab")
		)
		(fp_line
			(start 0.67945 -0.3048)
			(end 0.67945 0.3048)
			(stroke
				(width 0.1)
				(type default)
			)
			(layer "F.Fab")
		)
		(fp_line
			(start 0.67945 0.3048)
			(end 0.120396 0.3048)
			(stroke
				(width 0.1)
				(type default)
			)
			(layer "F.Fab")
		)
		(pad "1" smd circle
			(at -0.40005 0)
			(size 0 0)
			(layers "F.Cu" "F.Mask" "F.Paste")
			(net "PCA9548_PCIE0_ADDR2")
		)
		(pad "2" smd circle
			(at 0.40005 0)
			(size 0 0)
			(layers "F.Cu" "F.Mask" "F.Paste")
			(net "GND")
		)
	)
	(footprint ""
		(layer "F.Cu")
		(at 442.419486 -22.673056 180)
		(property "Reference" "C1111"
			(at 0 0 180)
			(layer "F.SilkS")
			(hide yes)
			(effects
				(font
					(size 1.27 1.27)
				)
			)
		)
		(property "Value" ""
			(at 0 0 180)
			(layer "F.Fab")
			(effects
				(font
					(size 1.27 1.27)
				)
			)
		)
		(duplicate_pad_numbers_are_jumpers no)
		(fp_line
			(start 0.7874 0.4064)
			(end -0.7874 0.4064)
			(stroke
				(width 0.1524)
				(type default)
			)
			(layer "F.SilkS")
		)
		(fp_line
			(start 0.7874 -0.4064)
			(end 0.7874 0.4064)
			(stroke
				(width 0.1524)
				(type default)
			)
			(layer "F.SilkS")
		)
		(fp_line
			(start -0.7874 0.4064)
			(end -0.7874 -0.4064)
			(stroke
				(width 0.1524)
				(type default)
			)
			(layer "F.SilkS")
		)
		(fp_line
			(start -0.7874 -0.4064)
			(end 0.7874 -0.4064)
			(stroke
				(width 0.1524)
				(type default)
			)
			(layer "F.SilkS")
		)
		(fp_line
			(start 0.67945 0.3048)
			(end 0.120396 0.3048)
			(stroke
				(width 0.1)
				(type default)
			)
			(layer "F.Fab")
		)
		(fp_line
			(start 0.67945 -0.3048)
			(end 0.67945 0.3048)
			(stroke
				(width 0.1)
				(type default)
			)
			(layer "F.Fab")
		)
		(fp_line
			(start 0.12065 -0.2794)
			(end 0.12065 -0.3048)
			(stroke
				(width 0.1)
				(type default)
			)
			(layer "F.Fab")
		)
		(fp_line
			(start 0.12065 -0.3048)
			(end 0.67945 -0.3048)
			(stroke
				(width 0.1)
				(type default)
			)
			(layer "F.Fab")
		)
		(fp_line
			(start 0.120396 0.3048)
			(end 0.120396 0.2794)
			(stroke
				(width 0.1)
				(type default)
			)
			(layer "F.Fab")
		)
		(fp_line
			(start 0.120396 0.2794)
			(end -0.12065 0.2794)
			(stroke
				(width 0.1)
				(type default)
			)
			(layer "F.Fab")
		)
		(fp_line
			(start -0.12065 0.3048)
			(end -0.67945 0.3048)
			(stroke
				(width 0.1)
				(type default)
			)
			(layer "F.Fab")
		)
		(fp_line
			(start -0.12065 0.2794)
			(end -0.12065 0.3048)
			(stroke
				(width 0.1)
				(type default)
			)
			(layer "F.Fab")
		)
		(fp_line
			(start -0.12065 -0.2794)
			(end 0.12065 -0.2794)
			(stroke
				(width 0.1)
				(type default)
			)
			(layer "F.Fab")
		)
		(fp_line
			(start -0.12065 -0.305054)
			(end -0.12065 -0.2794)
			(stroke
				(width 0.1)
				(type default)
			)
			(layer "F.Fab")
		)
		(fp_line
			(start -0.67945 0.3048)
			(end -0.67945 -0.305054)
			(stroke
				(width 0.1)
				(type default)
			)
			(layer "F.Fab")
		)
		(fp_line
			(start -0.67945 -0.305054)
			(end -0.12065 -0.305054)
			(stroke
				(width 0.1)
				(type default)
			)
			(layer "F.Fab")
		)
		(pad "1" smd circle
			(at -0.40005 0 180)
			(size 0 0)
			(layers "F.Cu" "F.Mask" "F.Paste")
			(net "VSENSE_P12V_INA230_6_INP")
		)
		(pad "2" smd circle
			(at 0.40005 0 180)
			(size 0 0)
			(layers "F.Cu" "F.Mask" "F.Paste")
			(net "VSENSE_P12V_INA230_6_INN")
		)
	)
)
